#ISCELL
  mstr_misc dns *
  *
#ISCELL
  mstr_symbols cad_note *
  *
#ISCELL
  mstr_symbols intel_corp_bpage *
  *
#CELL
  w_hdl h5an4g6nafr-tfc-gp *
  page149_i1
#ISCELL
  mstr_standard offpage *
  page149_i10
#ISCELL
  mstr_symbols p3v3_stby *
  page149_i108
#CELL
  mstr_discrete fet_n_dual *
  page149_i109
#ISCELL
  mstr_standard offpage *
  page149_i11
#ISCELL
  mstr_symbols gnd *
  page149_i110
#CELL
  mstr_discrete res *
  page149_i111
#ISCELL
  mstr_symbols gnd *
  page149_i112
#CELL
  mstr_discrete fet_n_dual *
  page149_i113
#ISCELL
  mstr_standard offpage *
  page149_i114
#ISCELL
  mstr_standard offpage *
  page149_i115
#ISCELL
  mstr_standard offpage *
  page149_i116
#ISCELL
  mstr_standard offpage *
  page149_i117
#ISCELL
  w_power w_vcc_circle *
  page149_i119
#ISCELL
  mstr_standard offpage *
  page149_i12
#CELL
  mstr_discrete res *
  page149_i120
#ISCELL
  mstr_symbols gnd *
  page149_i121
#CELL
  mstr_discrete res *
  page149_i122
#ISCELL
  w_power w_vcc_circle *
  page149_i123
#CELL
  mstr_discrete res *
  page149_i124
#CELL
  mstr_discrete res *
  page149_i125
#CELL
  mstr_discrete cap *
  page149_i126
#ISCELL
  mstr_symbols gnd *
  page149_i127
#ISCELL
  mstr_standard offpage *
  page149_i13
#CELL
  mstr_discrete res *
  page149_i14
#ISCELL
  w_power w_vcc_circle *
  page149_i15
#ISCELL
  mstr_symbols gnd *
  page149_i154
#ISCELL
  mstr_symbols p3v3_stby *
  page149_i155
#CELL
  mstr_discrete res *
  page149_i156
#ISCELL
  mstr_standard offpage *
  page149_i157
#CELL
  mstr_discrete cap *
  page149_i158
#CELL
  mstr_discrete cap *
  page149_i159
#CELL
  mstr_discrete res *
  page149_i16
#CELL
  w_hdl 120r2f-gp *
  page149_i160
#CELL
  w_hdl 120r2f-gp *
  page149_i161
#CELL
  w_hdl 120r2f-gp *
  page149_i162
#CELL
  w_hdl 120r2f-gp *
  page149_i163
#CELL
  w_hdl 120r2f-gp *
  page149_i164
#CELL
  w_hdl 120r2f-gp *
  page149_i165
#CELL
  w_hdl 120r2f-gp *
  page149_i166
#CELL
  w_hdl 120r2f-gp *
  page149_i167
#CELL
  w_hdl 120r2f-gp *
  page149_i168
#CELL
  w_hdl 120r2f-gp *
  page149_i169
#ISCELL
  mstr_standard offpage *
  page149_i17
#CELL
  w_hdl 120r2f-gp *
  page149_i170
#CELL
  w_hdl 120r2f-gp *
  page149_i171
#CELL
  w_hdl 120r2f-gp *
  page149_i172
#CELL
  w_hdl 120r2f-gp *
  page149_i173
#CELL
  w_hdl 120r2f-gp *
  page149_i174
#CELL
  w_hdl 120r2f-gp *
  page149_i175
#CELL
  w_hdl 120r2f-gp *
  page149_i176
#CELL
  w_hdl 120r2f-gp *
  page149_i177
#CELL
  w_hdl 120r2f-gp *
  page149_i178
#CELL
  w_hdl 120r2f-gp *
  page149_i179
#ISCELL
  mstr_standard offpage *
  page149_i18
#CELL
  w_hdl 120r2f-gp *
  page149_i180
#CELL
  w_hdl 120r2f-gp *
  page149_i181
#CELL
  w_hdl 120r2f-gp *
  page149_i182
#CELL
  w_hdl 120r2f-gp *
  page149_i183
#CELL
  w_hdl 120r2f-gp *
  page149_i184
#CELL
  w_hdl 120r2f-gp *
  page149_i185
#CELL
  w_hdl 120r2f-gp *
  page149_i186
#CELL
  w_hdl 120r2f-gp *
  page149_i187
#CELL
  w_hdl 120r2f-gp *
  page149_i188
#CELL
  w_hdl 120r2f-gp *
  page149_i189
#ISCELL
  mstr_standard offpage *
  page149_i19
#CELL
  w_hdl 120r2f-gp *
  page149_i190
#CELL
  w_hdl 120r2f-gp *
  page149_i191
#CELL
  w_hdl 120r2f-gp *
  page149_i192
#CELL
  w_hdl 120r2f-gp *
  page149_i193
#CELL
  w_hdl 120r2f-gp *
  page149_i194
#CELL
  w_hdl 120r2f-gp *
  page149_i195
#CELL
  w_hdl 120r2f-gp *
  page149_i196
#CELL
  w_hdl 120r2f-gp *
  page149_i197
#CELL
  w_hdl 120r2f-gp *
  page149_i198
#CELL
  w_hdl 120r2f-gp *
  page149_i199
#ISCELL
  mstr_standard offpage *
  page149_i2
#ISCELL
  mstr_standard offpage *
  page149_i20
#CELL
  w_hdl 120r2f-gp *
  page149_i200
#CELL
  w_hdl 120r2f-gp *
  page149_i201
#CELL
  w_hdl 120r2f-gp *
  page149_i202
#CELL
  w_hdl 120r2f-gp *
  page149_i203
#CELL
  w_hdl 120r2f-gp *
  page149_i204
#CELL
  w_hdl 120r2f-gp *
  page149_i205
#CELL
  w_hdl 120r2f-gp *
  page149_i206
#CELL
  w_hdl 120r2f-gp *
  page149_i207
#CELL
  w_hdl 120r2f-gp *
  page149_i208
#CELL
  w_hdl 120r2f-gp *
  page149_i209
#ISCELL
  mstr_standard offpage *
  page149_i21
#CELL
  w_hdl 120r2f-gp *
  page149_i210
#CELL
  w_hdl 120r2f-gp *
  page149_i211
#CELL
  w_hdl 120r2f-gp *
  page149_i212
#ISCELL
  mstr_standard offpage *
  page149_i22
#ISCELL
  mstr_standard offpage *
  page149_i23
#ISCELL
  mstr_standard offpage *
  page149_i24
#ISCELL
  mstr_standard offpage *
  page149_i25
#ISCELL
  mstr_standard offpage *
  page149_i26
#ISCELL
  mstr_standard offpage *
  page149_i27
#ISCELL
  mstr_standard offpage *
  page149_i28
#ISCELL
  mstr_standard offpage *
  page149_i29
#ISCELL
  mstr_standard offpage *
  page149_i3
#ISCELL
  mstr_standard offpage *
  page149_i30
#ISCELL
  mstr_standard offpage *
  page149_i31
#ISCELL
  mstr_standard offpage *
  page149_i32
#ISCELL
  mstr_symbols gnd *
  page149_i33
#CELL
  mstr_ttl ttl1g07_a *
  page149_i34
#ISCELL
  w_power w_vcc_circle *
  page149_i35
#ISCELL
  mstr_standard offpage *
  page149_i36
#CELL
  mstr_discrete cap *
  page149_i37
#CELL
  w_hdl sc1u16v3kx-2gp *
  page149_i38
#CELL
  w_hdl scd1u16v2kx-3gp *
  page149_i39
#ISCELL
  mstr_standard offpage *
  page149_i4
#ISCELL
  w_power w_vcc_circle *
  page149_i40
#ISCELL
  mstr_standard offpage *
  page149_i41
#ISCELL
  mstr_standard offpage *
  page149_i42
#ISCELL
  mstr_standard offpage *
  page149_i43
#CELL
  w_hdl scd1u16v2kx-3gp *
  page149_i44
#ISCELL
  mstr_symbols gnd *
  page149_i45
#ISCELL
  mstr_standard offpage *
  page149_i46
#ISCELL
  mstr_standard offpage *
  page149_i47
#ISCELL
  mstr_standard offpage *
  page149_i48
#ISCELL
  mstr_standard offpage *
  page149_i49
#ISCELL
  mstr_standard offpage *
  page149_i5
#ISCELL
  mstr_standard offpage *
  page149_i50
#ISCELL
  mstr_standard offpage *
  page149_i51
#ISCELL
  mstr_standard offpage *
  page149_i52
#ISCELL
  mstr_standard offpage *
  page149_i53
#ISCELL
  mstr_standard offpage *
  page149_i54
#CELL
  mstr_discrete res *
  page149_i55
#ISCELL
  mstr_symbols gnd *
  page149_i56
#ISCELL
  mstr_standard offpage *
  page149_i57
#ISCELL
  mstr_standard offpage *
  page149_i58
#ISCELL
  mstr_standard offpage *
  page149_i59
#ISCELL
  mstr_standard offpage *
  page149_i6
#ISCELL
  mstr_standard offpage *
  page149_i60
#ISCELL
  mstr_standard offpage *
  page149_i61
#ISCELL
  mstr_standard offpage *
  page149_i62
#ISCELL
  mstr_standard offpage *
  page149_i63
#ISCELL
  mstr_standard offpage *
  page149_i64
#CELL
  mstr_discrete cap *
  page149_i65
#ISCELL
  mstr_symbols gnd *
  page149_i66
#ISCELL
  w_power w_vcc_circle *
  page149_i67
#CELL
  w_hdl sc1u16v3kx-2gp *
  page149_i68
#CELL
  w_hdl sc4d7u10v3kx-gp *
  page149_i69
#ISCELL
  mstr_standard offpage *
  page149_i7
#ISCELL
  mstr_symbols gnd *
  page149_i70
#CELL
  mstr_discrete cap *
  page149_i71
#CELL
  mstr_discrete cap *
  page149_i72
#CELL
  mstr_discrete cap *
  page149_i73
#CELL
  mstr_discrete cap *
  page149_i74
#ISCELL
  w_power w_vcc_circle *
  page149_i75
#ISCELL
  mstr_standard offpage *
  page149_i8
#ISCELL
  mstr_standard offpage *
  page149_i9
#ISCELL
  mstr_symbols p3v3_stby *
  page149_i93
#CELL
  mstr_discrete res *
  page149_i94
#ISCELL
  mstr_symbols gnd *
  page149_i95
#CELL
  mstr_discrete cap *
  page149_i96
#CELL
  mstr_discrete cap *
  page149_i97
#CELL
  mstr_discrete led *
  page149_i98
